(kicad_pcb
	(version 20260206)
	(generator "pcbnew")
	(generator_version "10.0")
	(general
		(thickness 1.6)
		(legacy_teardrops no)
	)
	(paper "A4")
	(title_block
		(title "Bryce Canyon_SCC_16316-1_OCP.brd")
		(comment 1 "Bryce Canyon / footprint 64 of 1561 (U1), pads 350-464 of 1020")
	)
	(layers
		(0 "F.Cu" signal "TOP")
		(4 "In1.Cu" signal "L2GND")
		(6 "In2.Cu" signal "L3")
		(8 "In3.Cu" signal "L4VCC")
		(10 "In4.Cu" signal "L5VCC")
		(12 "In5.Cu" signal "L6")
		(14 "In6.Cu" signal "L7GND")
		(2 "B.Cu" signal "BOTTOM")
		(9 "F.Adhes" user "F.Adhesive")
		(11 "B.Adhes" user "B.Adhesive")
		(13 "F.Paste" user "Package Geometry/Pastemask Top")
		(15 "B.Paste" user "Package Geometry/Pastemask Bottom")
		(5 "F.SilkS" user "Ref Des/Silkscreen Top")
		(7 "B.SilkS" user "Ref Des/Silkscreen Bottom")
		(1 "F.Mask" user "Board Geometry/Soldermask Top")
		(3 "B.Mask" user "Board Geometry/Soldermask Bottom")
		(17 "Dwgs.User" user "User.Drawings")
		(19 "Cmts.User" user "User.Comments")
		(21 "Eco1.User" user "User.Eco1")
		(23 "Eco2.User" user "User.Eco2")
		(25 "Edge.Cuts" user "Board Geometry/Outline")
		(27 "Margin" user)
		(31 "F.CrtYd" user "Package Geometry/Place Bound Top")
		(29 "B.CrtYd" user "Package Geometry/Place Bound Bottom")
		(35 "F.Fab" user "Ref Des/Assembly Top")
		(33 "B.Fab" user "Ref Des/Assembly Bottom")
	)
	(footprint ""
		(layer "F.Cu")
		(at 115.000024 -67.00012)
		(property "Reference" "U1"
			(at 0 0 0)
			(layer "F.SilkS")
			(hide yes)
			(effects
				(font
					(size 1.27 1.27)
				)
			)
		)
		(property "Value" "LSISAS3X48-GP"
			(at -24.358092 -5.0292 0)
			(unlocked yes)
			(layer "F.Fab")
			(hide yes)
			(effects
				(font
					(size 1.016 1.016)
					(thickness 0.1524)
				)
			)
		)
		(property "Device Type" "BGA1020C33H83"
			(at -24.358092 -6.5532 0)
			(unlocked yes)
			(layer "F.Fab")
			(hide yes)
			(effects
				(font
					(size 1.016 1.016)
					(thickness 0.1524)
				)
			)
		)
		(duplicate_pad_numbers_are_jumpers no)
		(pad "AK32" smd circle
			(at 15.500096 13.5001)
			(size 0.508 0.508)
			(layers "F.Cu" "F.Mask" "F.Paste")
			(net "GND")
		)
		(pad "AL1" smd circle
			(at -15.500096 14.500098)
			(size 0.508 0.508)
			(layers "F.Cu" "F.Mask" "F.Paste")
			(net "GND")
		)
		(pad "AL2" smd circle
			(at -14.500098 14.500098)
			(size 0.508 0.508)
			(layers "F.Cu" "F.Mask" "F.Paste")
			(net "PHY_SCC_TO_DPB_12_DN")
		)
		(pad "AL3" smd circle
			(at -13.5001 14.500098)
			(size 0.508 0.508)
			(layers "F.Cu" "F.Mask" "F.Paste")
			(net "PHY_SCC_TO_DPB_13_DP")
		)
		(pad "AL4" smd circle
			(at -12.500102 14.500098)
			(size 0.4572 0.4572)
			(layers "F.Cu" "F.Mask" "F.Paste")
			(net "PHY_SCC_TO_DPB_14_DN")
		)
		(pad "AL5" smd circle
			(at -11.500104 14.500098)
			(size 0.4572 0.4572)
			(layers "F.Cu" "F.Mask" "F.Paste")
			(net "PHY_SCC_TO_DPB_15_DP")
		)
		(pad "AL6" smd circle
			(at -10.500106 14.500098)
			(size 0.4572 0.4572)
			(layers "F.Cu" "F.Mask" "F.Paste")
			(net "PHY_SCC_TO_DPB_16_DN")
		)
		(pad "AL7" smd circle
			(at -9.500108 14.500098)
			(size 0.4572 0.4572)
			(layers "F.Cu" "F.Mask" "F.Paste")
			(net "PHY_SCC_TO_DPB_17_DP")
		)
		(pad "AL8" smd circle
			(at -8.50011 14.500098)
			(size 0.4572 0.4572)
			(layers "F.Cu" "F.Mask" "F.Paste")
			(net "PHY_SCC_TO_DPB_18_DN")
		)
		(pad "AL9" smd circle
			(at -7.500112 14.500098)
			(size 0.4572 0.4572)
			(layers "F.Cu" "F.Mask" "F.Paste")
			(net "PHY_SCC_TO_DPB_19_DP")
		)
		(pad "AL10" smd circle
			(at -6.500114 14.500098)
			(size 0.4572 0.4572)
			(layers "F.Cu" "F.Mask" "F.Paste")
			(net "PHY_SCC_TO_DPB_20_DN")
		)
		(pad "AL11" smd circle
			(at -5.500116 14.500098)
			(size 0.4572 0.4572)
			(layers "F.Cu" "F.Mask" "F.Paste")
			(net "PHY_SCC_TO_DPB_21_DP")
		)
		(pad "AL12" smd circle
			(at -4.500118 14.500098)
			(size 0.4572 0.4572)
			(layers "F.Cu" "F.Mask" "F.Paste")
			(net "PHY_SCC_TO_DPB_22_DN")
		)
		(pad "AL13" smd circle
			(at -3.50012 14.500098)
			(size 0.4572 0.4572)
			(layers "F.Cu" "F.Mask" "F.Paste")
			(net "PHY_SCC_TO_DPB_23_DP")
		)
		(pad "AL14" smd circle
			(at -2.500122 14.500098)
			(size 0.4572 0.4572)
			(layers "F.Cu" "F.Mask" "F.Paste")
			(net "PHY_SCC_TO_DPB_24_DN")
		)
		(pad "AL15" smd circle
			(at -1.500124 14.500098)
			(size 0.4572 0.4572)
			(layers "F.Cu" "F.Mask" "F.Paste")
			(net "PHY_SCC_TO_DPB_25_DP")
		)
		(pad "AL16" smd circle
			(at -0.500126 14.500098)
			(size 0.4572 0.4572)
			(layers "F.Cu" "F.Mask" "F.Paste")
			(net "PHY_SCC_TO_DPB_26_DN")
		)
		(pad "AL17" smd circle
			(at 0.500126 14.500098)
			(size 0.4572 0.4572)
			(layers "F.Cu" "F.Mask" "F.Paste")
			(net "PHY_SCC_TO_DPB_27_DP")
		)
		(pad "AL18" smd circle
			(at 1.500124 14.500098)
			(size 0.4572 0.4572)
			(layers "F.Cu" "F.Mask" "F.Paste")
			(net "PHY_SCC_TO_DPB_32_DN")
		)
		(pad "AL19" smd circle
			(at 2.500122 14.500098)
			(size 0.4572 0.4572)
			(layers "F.Cu" "F.Mask" "F.Paste")
			(net "PHY_SCC_TO_DPB_33_DP")
		)
		(pad "AL20" smd circle
			(at 3.50012 14.500098)
			(size 0.4572 0.4572)
			(layers "F.Cu" "F.Mask" "F.Paste")
			(net "PHY_SCC_TO_DPB_34_DN")
		)
		(pad "AL21" smd circle
			(at 4.500118 14.500098)
			(size 0.4572 0.4572)
			(layers "F.Cu" "F.Mask" "F.Paste")
			(net "PHY_SCC_TO_DPB_35_DP")
		)
		(pad "AL22" smd circle
			(at 5.500116 14.500098)
			(size 0.4572 0.4572)
			(layers "F.Cu" "F.Mask" "F.Paste")
			(net "PHY_SCC_TO_DPB_36_DN")
		)
		(pad "AL23" smd circle
			(at 6.500114 14.500098)
			(size 0.4572 0.4572)
			(layers "F.Cu" "F.Mask" "F.Paste")
			(net "PHY_SCC_TO_DPB_37_DP")
		)
		(pad "AL24" smd circle
			(at 7.500112 14.500098)
			(size 0.4572 0.4572)
			(layers "F.Cu" "F.Mask" "F.Paste")
			(net "PHY_SCC_TO_DPB_38_DN")
		)
		(pad "AL25" smd circle
			(at 8.50011 14.500098)
			(size 0.4572 0.4572)
			(layers "F.Cu" "F.Mask" "F.Paste")
			(net "PHY_SCC_TO_DPB_39_DP")
		)
		(pad "AL26" smd circle
			(at 9.500108 14.500098)
			(size 0.4572 0.4572)
			(layers "F.Cu" "F.Mask" "F.Paste")
			(net "GND")
		)
		(pad "AL27" smd circle
			(at 10.500106 14.500098)
			(size 0.4572 0.4572)
			(layers "F.Cu" "F.Mask" "F.Paste")
			(net "GND")
		)
		(pad "AL28" smd circle
			(at 11.500104 14.500098)
			(size 0.4572 0.4572)
			(layers "F.Cu" "F.Mask" "F.Paste")
			(net "GND")
		)
		(pad "AL29" smd circle
			(at 12.500102 14.500098)
			(size 0.4572 0.4572)
			(layers "F.Cu" "F.Mask" "F.Paste")
			(net "GND")
		)
		(pad "AL30" smd circle
			(at 13.5001 14.500098)
			(size 0.508 0.508)
			(layers "F.Cu" "F.Mask" "F.Paste")
			(net "GND")
		)
		(pad "AL31" smd circle
			(at 14.500098 14.500098)
			(size 0.508 0.508)
			(layers "F.Cu" "F.Mask" "F.Paste")
			(net "PHY_SCC_TO_IOC_40_DN")
		)
		(pad "AL32" smd circle
			(at 15.500096 14.500098)
			(size 0.508 0.508)
			(layers "F.Cu" "F.Mask" "F.Paste")
			(net "PHY_SCC_TO_IOC_40_DP")
		)
		(pad "AM2" smd circle
			(at -14.500098 15.500096)
			(size 0.508 0.508)
			(layers "F.Cu" "F.Mask" "F.Paste")
			(net "PHY_SCC_TO_DPB_12_DP")
		)
		(pad "AM3" smd circle
			(at -13.5001 15.500096)
			(size 0.508 0.508)
			(layers "F.Cu" "F.Mask" "F.Paste")
			(net "GND")
		)
		(pad "AM4" smd circle
			(at -12.500102 15.500096)
			(size 0.4572 0.4572)
			(layers "F.Cu" "F.Mask" "F.Paste")
			(net "PHY_SCC_TO_DPB_14_DP")
		)
		(pad "AM5" smd circle
			(at -11.500104 15.500096)
			(size 0.4572 0.4572)
			(layers "F.Cu" "F.Mask" "F.Paste")
			(net "GND")
		)
		(pad "AM6" smd circle
			(at -10.500106 15.500096)
			(size 0.4572 0.4572)
			(layers "F.Cu" "F.Mask" "F.Paste")
			(net "PHY_SCC_TO_DPB_16_DP")
		)
		(pad "AM7" smd circle
			(at -9.500108 15.500096)
			(size 0.4572 0.4572)
			(layers "F.Cu" "F.Mask" "F.Paste")
			(net "GND")
		)
		(pad "AM8" smd circle
			(at -8.50011 15.500096)
			(size 0.4572 0.4572)
			(layers "F.Cu" "F.Mask" "F.Paste")
			(net "PHY_SCC_TO_DPB_18_DP")
		)
		(pad "AM9" smd circle
			(at -7.500112 15.500096)
			(size 0.4572 0.4572)
			(layers "F.Cu" "F.Mask" "F.Paste")
			(net "GND")
		)
		(pad "AM10" smd circle
			(at -6.500114 15.500096)
			(size 0.4572 0.4572)
			(layers "F.Cu" "F.Mask" "F.Paste")
			(net "PHY_SCC_TO_DPB_20_DP")
		)
		(pad "AM11" smd circle
			(at -5.500116 15.500096)
			(size 0.4572 0.4572)
			(layers "F.Cu" "F.Mask" "F.Paste")
			(net "GND")
		)
		(pad "AM12" smd circle
			(at -4.500118 15.500096)
			(size 0.4572 0.4572)
			(layers "F.Cu" "F.Mask" "F.Paste")
			(net "PHY_SCC_TO_DPB_22_DP")
		)
		(pad "AM13" smd circle
			(at -3.50012 15.500096)
			(size 0.4572 0.4572)
			(layers "F.Cu" "F.Mask" "F.Paste")
			(net "GND")
		)
		(pad "AM14" smd circle
			(at -2.500122 15.500096)
			(size 0.4572 0.4572)
			(layers "F.Cu" "F.Mask" "F.Paste")
			(net "PHY_SCC_TO_DPB_24_DP")
		)
		(pad "AM15" smd circle
			(at -1.500124 15.500096)
			(size 0.4572 0.4572)
			(layers "F.Cu" "F.Mask" "F.Paste")
			(net "GND")
		)
		(pad "AM16" smd circle
			(at -0.500126 15.500096)
			(size 0.4572 0.4572)
			(layers "F.Cu" "F.Mask" "F.Paste")
			(net "PHY_SCC_TO_DPB_26_DP")
		)
		(pad "AM17" smd circle
			(at 0.500126 15.500096)
			(size 0.4572 0.4572)
			(layers "F.Cu" "F.Mask" "F.Paste")
			(net "GND")
		)
		(pad "AM18" smd circle
			(at 1.500124 15.500096)
			(size 0.4572 0.4572)
			(layers "F.Cu" "F.Mask" "F.Paste")
			(net "PHY_SCC_TO_DPB_32_DP")
		)
		(pad "AM19" smd circle
			(at 2.500122 15.500096)
			(size 0.4572 0.4572)
			(layers "F.Cu" "F.Mask" "F.Paste")
			(net "GND")
		)
		(pad "AM20" smd circle
			(at 3.50012 15.500096)
			(size 0.4572 0.4572)
			(layers "F.Cu" "F.Mask" "F.Paste")
			(net "PHY_SCC_TO_DPB_34_DP")
		)
		(pad "AM21" smd circle
			(at 4.500118 15.500096)
			(size 0.4572 0.4572)
			(layers "F.Cu" "F.Mask" "F.Paste")
			(net "GND")
		)
		(pad "AM22" smd circle
			(at 5.500116 15.500096)
			(size 0.4572 0.4572)
			(layers "F.Cu" "F.Mask" "F.Paste")
			(net "PHY_SCC_TO_DPB_36_DP")
		)
		(pad "AM23" smd circle
			(at 6.500114 15.500096)
			(size 0.4572 0.4572)
			(layers "F.Cu" "F.Mask" "F.Paste")
			(net "GND")
		)
		(pad "AM24" smd circle
			(at 7.500112 15.500096)
			(size 0.4572 0.4572)
			(layers "F.Cu" "F.Mask" "F.Paste")
			(net "PHY_SCC_TO_DPB_38_DP")
		)
		(pad "AM25" smd circle
			(at 8.50011 15.500096)
			(size 0.4572 0.4572)
			(layers "F.Cu" "F.Mask" "F.Paste")
			(net "GND")
		)
		(pad "AM26" smd circle
			(at 9.500108 15.500096)
			(size 0.4572 0.4572)
			(layers "F.Cu" "F.Mask" "F.Paste")
			(net "GND")
		)
		(pad "AM27" smd circle
			(at 10.500106 15.500096)
			(size 0.4572 0.4572)
			(layers "F.Cu" "F.Mask" "F.Paste")
			(net "GND")
		)
		(pad "AM28" smd circle
			(at 11.500104 15.500096)
			(size 0.4572 0.4572)
			(layers "F.Cu" "F.Mask" "F.Paste")
			(net "RTRIM_A")
		)
		(pad "AM29" smd circle
			(at 12.500102 15.500096)
			(size 0.4572 0.4572)
			(layers "F.Cu" "F.Mask" "F.Paste")
			(net "RTRIM_AN")
		)
		(pad "AM30" smd circle
			(at 13.5001 15.500096)
			(size 0.508 0.508)
			(layers "F.Cu" "F.Mask" "F.Paste")
			(net "GND")
		)
		(pad "AM31" smd circle
			(at 14.500098 15.500096)
			(size 0.508 0.508)
			(layers "F.Cu" "F.Mask" "F.Paste")
			(net "GND")
		)
		(pad "B1" smd circle
			(at -15.500096 -14.500098)
			(size 0.508 0.508)
			(layers "F.Cu" "F.Mask" "F.Paste")
			(net "Net_1258")
		)
		(pad "B2" smd circle
			(at -14.500098 -14.500098)
			(size 0.508 0.508)
			(layers "F.Cu" "F.Mask" "F.Paste")
			(net "VDDIO_DDR")
		)
		(pad "B3" smd circle
			(at -13.5001 -14.500098)
			(size 0.508 0.508)
			(layers "F.Cu" "F.Mask" "F.Paste")
			(net "Net_1257")
		)
		(pad "B4" smd circle
			(at -12.500102 -14.500098)
			(size 0.4572 0.4572)
			(layers "F.Cu" "F.Mask" "F.Paste")
			(net "VDDIO_DDR")
		)
		(pad "B5" smd circle
			(at -11.500104 -14.500098)
			(size 0.4572 0.4572)
			(layers "F.Cu" "F.Mask" "F.Paste")
			(net "Net_1256")
		)
		(pad "B6" smd circle
			(at -10.500106 -14.500098)
			(size 0.4572 0.4572)
			(layers "F.Cu" "F.Mask" "F.Paste")
			(net "GND")
		)
		(pad "B7" smd circle
			(at -9.500108 -14.500098)
			(size 0.4572 0.4572)
			(layers "F.Cu" "F.Mask" "F.Paste")
			(net "DRIVE_5_ACT")
		)
		(pad "B8" smd circle
			(at -8.50011 -14.500098)
			(size 0.4572 0.4572)
			(layers "F.Cu" "F.Mask" "F.Paste")
			(net "DRIVE_1_ACT")
		)
		(pad "B9" smd circle
			(at -7.500112 -14.500098)
			(size 0.4572 0.4572)
			(layers "F.Cu" "F.Mask" "F.Paste")
			(net "SXP_ACTIVE_2")
		)
		(pad "B10" smd circle
			(at -6.500114 -14.500098)
			(size 0.4572 0.4572)
			(layers "F.Cu" "F.Mask" "F.Paste")
			(net "JTAG_EXP_TMS")
		)
		(pad "B11" smd circle
			(at -5.500116 -14.500098)
			(size 0.4572 0.4572)
			(layers "F.Cu" "F.Mask" "F.Paste")
			(net "SOFT_RESET_N")
		)
		(pad "B12" smd circle
			(at -4.500118 -14.500098)
			(size 0.4572 0.4572)
			(layers "F.Cu" "F.Mask" "F.Paste")
			(net "EXP_XM_OE_N")
		)
		(pad "B13" smd circle
			(at -3.50012 -14.500098)
			(size 0.4572 0.4572)
			(layers "F.Cu" "F.Mask" "F.Paste")
			(net "XM_DATA5")
		)
		(pad "B14" smd circle
			(at -2.500122 -14.500098)
			(size 0.4572 0.4572)
			(layers "F.Cu" "F.Mask" "F.Paste")
			(net "XM_DATA2")
		)
		(pad "B15" smd circle
			(at -1.500124 -14.500098)
			(size 0.4572 0.4572)
			(layers "F.Cu" "F.Mask" "F.Paste")
			(net "XM_DATA10")
		)
		(pad "B16" smd circle
			(at -0.500126 -14.500098)
			(size 0.4572 0.4572)
			(layers "F.Cu" "F.Mask" "F.Paste")
			(net "EXP_XM_ADDR_4")
		)
		(pad "B17" smd circle
			(at 0.500126 -14.500098)
			(size 0.4572 0.4572)
			(layers "F.Cu" "F.Mask" "F.Paste")
			(net "EXP_XM_ADDR_3")
		)
		(pad "B18" smd circle
			(at 1.500124 -14.500098)
			(size 0.4572 0.4572)
			(layers "F.Cu" "F.Mask" "F.Paste")
			(net "EXP_XM_ADDR_16")
		)
		(pad "B19" smd circle
			(at 2.500122 -14.500098)
			(size 0.4572 0.4572)
			(layers "F.Cu" "F.Mask" "F.Paste")
			(net "EXP_XM_ADDR_0")
		)
		(pad "B20" smd circle
			(at 3.50012 -14.500098)
			(size 0.4572 0.4572)
			(layers "F.Cu" "F.Mask" "F.Paste")
			(net "EXP_GPIO13")
		)
		(pad "B21" smd circle
			(at 4.500118 -14.500098)
			(size 0.4572 0.4572)
			(layers "F.Cu" "F.Mask" "F.Paste")
			(net "SCC_TYPE_2_LS")
		)
		(pad "B22" smd circle
			(at 5.500116 -14.500098)
			(size 0.4572 0.4572)
			(layers "F.Cu" "F.Mask" "F.Paste")
			(net "USB_NXT")
		)
		(pad "B23" smd circle
			(at 6.500114 -14.500098)
			(size 0.4572 0.4572)
			(layers "F.Cu" "F.Mask" "F.Paste")
			(net "Net_1212")
		)
		(pad "B24" smd circle
			(at 7.500112 -14.500098)
			(size 0.4572 0.4572)
			(layers "F.Cu" "F.Mask" "F.Paste")
			(net "PHY_CLK")
		)
		(pad "B25" smd circle
			(at 8.50011 -14.500098)
			(size 0.4572 0.4572)
			(layers "F.Cu" "F.Mask" "F.Paste")
			(net "Net_1211")
		)
		(pad "B26" smd circle
			(at 9.500108 -14.500098)
			(size 0.4572 0.4572)
			(layers "F.Cu" "F.Mask" "F.Paste")
			(net "Net_1210")
		)
		(pad "B27" smd circle
			(at 10.500106 -14.500098)
			(size 0.4572 0.4572)
			(layers "F.Cu" "F.Mask" "F.Paste")
			(net "SDB_R_TX")
		)
		(pad "B28" smd circle
			(at 11.500104 -14.500098)
			(size 0.4572 0.4572)
			(layers "F.Cu" "F.Mask" "F.Paste")
			(net "SMART_RX")
		)
		(pad "B29" smd circle
			(at 12.500102 -14.500098)
			(size 0.4572 0.4572)
			(layers "F.Cu" "F.Mask" "F.Paste")
			(net "EXP_SIO_D_IN")
		)
		(pad "B30" smd circle
			(at 13.5001 -14.500098)
			(size 0.508 0.508)
			(layers "F.Cu" "F.Mask" "F.Paste")
			(net "EXP_I2C_SDA10")
		)
		(pad "B31" smd circle
			(at 14.500098 -14.500098)
			(size 0.508 0.508)
			(layers "F.Cu" "F.Mask" "F.Paste")
			(net "I2C_EXP_IOC_SCL8")
		)
		(pad "B32" smd circle
			(at 15.500096 -14.500098)
			(size 0.508 0.508)
			(layers "F.Cu" "F.Mask" "F.Paste")
			(net "I2C_DRIVE_FLT_LED_SDA6_LS")
		)
		(pad "C1" smd circle
			(at -15.500096 -13.5001)
			(size 0.508 0.508)
			(layers "F.Cu" "F.Mask" "F.Paste")
			(net "Net_1255")
		)
		(pad "C2" smd circle
			(at -14.500098 -13.5001)
			(size 0.508 0.508)
			(layers "F.Cu" "F.Mask" "F.Paste")
			(net "Net_1254")
		)
		(pad "C3" smd circle
			(at -13.5001 -13.5001)
			(size 0.508 0.508)
			(layers "F.Cu" "F.Mask" "F.Paste")
			(net "GND")
		)
		(pad "C4" smd circle
			(at -12.500102 -13.5001)
			(size 0.4572 0.4572)
			(layers "F.Cu" "F.Mask" "F.Paste")
			(net "Net_1253")
		)
		(pad "C5" smd circle
			(at -11.500104 -13.5001)
			(size 0.4572 0.4572)
			(layers "F.Cu" "F.Mask" "F.Paste")
			(net "Net_1252")
		)
		(pad "C6" smd circle
			(at -10.500106 -13.5001)
			(size 0.4572 0.4572)
			(layers "F.Cu" "F.Mask" "F.Paste")
			(net "GND")
		)
		(pad "C7" smd circle
			(at -9.500108 -13.5001)
			(size 0.4572 0.4572)
			(layers "F.Cu" "F.Mask" "F.Paste")
			(net "DRIVE_6_ACT")
		)
		(pad "C8" smd circle
			(at -8.50011 -13.5001)
			(size 0.4572 0.4572)
			(layers "F.Cu" "F.Mask" "F.Paste")
			(net "GND")
		)
		(pad "C9" smd circle
			(at -7.500112 -13.5001)
			(size 0.4572 0.4572)
			(layers "F.Cu" "F.Mask" "F.Paste")
			(net "DRIVE_2_ACT")
		)
		(pad "C10" smd circle
			(at -6.500114 -13.5001)
			(size 0.4572 0.4572)
			(layers "F.Cu" "F.Mask" "F.Paste")
			(net "EXP_BLINK_IN")
		)
		(pad "C11" smd circle
			(at -5.500116 -13.5001)
			(size 0.4572 0.4572)
			(layers "F.Cu" "F.Mask" "F.Paste")
			(net "TMUX_EN")
		)
		(pad "C12" smd circle
			(at -4.500118 -13.5001)
			(size 0.4572 0.4572)
			(layers "F.Cu" "F.Mask" "F.Paste")
			(net "XM_WBE_1#_TP")
		)
		(pad "C13" smd circle
			(at -3.50012 -13.5001)
			(size 0.4572 0.4572)
			(layers "F.Cu" "F.Mask" "F.Paste")
			(net "XM_DATA7")
		)
		(pad "C14" smd circle
			(at -2.500122 -13.5001)
			(size 0.4572 0.4572)
			(layers "F.Cu" "F.Mask" "F.Paste")
			(net "GND")
		)
		(pad "C15" smd circle
			(at -1.500124 -13.5001)
			(size 0.4572 0.4572)
			(layers "F.Cu" "F.Mask" "F.Paste")
			(net "EXP_XM_BUSY_N")
		)
		(pad "C16" smd circle
			(at -0.500126 -13.5001)
			(size 0.4572 0.4572)
			(layers "F.Cu" "F.Mask" "F.Paste")
			(net "GND")
		)
		(pad "C17" smd circle
			(at 0.500126 -13.5001)
			(size 0.4572 0.4572)
			(layers "F.Cu" "F.Mask" "F.Paste")
			(net "EXP_XM_ADDR_23")
		)
		(pad "C18" smd circle
			(at 1.500124 -13.5001)
			(size 0.4572 0.4572)
			(layers "F.Cu" "F.Mask" "F.Paste")
			(net "GND")
		)
		(pad "C19" smd circle
			(at 2.500122 -13.5001)
			(size 0.4572 0.4572)
			(layers "F.Cu" "F.Mask" "F.Paste")
			(net "PWM_OUT_ZONE_D_LS")
		)
		(pad "C20" smd circle
			(at 3.50012 -13.5001)
			(size 0.4572 0.4572)
			(layers "F.Cu" "F.Mask" "F.Paste")
			(net "GND")
		)
	)
)
